# S9S_MB_2U (Grand Teton) — schematic netlist excerpt (pin names and nets, part order shuffled) for the footprints in the layout excerpt that follows; sources: Cadence DE-HDL packaged netlist, KiCad conversion of 03242023_DA0F0TMBIJ0_F0T_Motherboard_J_brd_V01_OCP.brd

C2321  Q_CAP  0.1UF 25V 10% EMPTY  pkg 0402  page 196 : A = PD_USB_HUB_2_RSTN ; B = GND
R57  Q_RES  200 1% CHIP  pkg 0402LF  page 45 : A = SVID_ALERT0_CPU1_N ; B = SVID_ALERT0_CPU1_R_N

(kicad_pcb
	(version 20260206)
	(generator "pcbnew")
	(generator_version "10.0")
	(general
		(thickness 1.6)
		(legacy_teardrops no)
	)
	(paper "A4")
	(title_block
		(title "03242023_DA0F0TMBIJ0_F0T_Motherboard_J_brd_V01_OCP.brd")
		(comment 1 "Grand Teton / footprints 5383-5384 of 6105")
	)
	(layers
		(0 "F.Cu" signal "TOP")
		(4 "In1.Cu" signal "GND")
		(6 "In2.Cu" signal "IN1")
		(8 "In3.Cu" signal "GND1")
		(10 "In4.Cu" signal "IN2")
		(12 "In5.Cu" signal "GND2")
		(14 "In6.Cu" signal "IN3")
		(16 "In7.Cu" signal "GND3")
		(18 "In8.Cu" signal "VCC")
		(20 "In9.Cu" signal "VCC1")
		(22 "In10.Cu" signal "GND4")
		(24 "In11.Cu" signal "IN4")
		(26 "In12.Cu" signal "GND5")
		(28 "In13.Cu" signal "IN5")
		(30 "In14.Cu" signal "GND6")
		(32 "In15.Cu" signal "IN6")
		(34 "In16.Cu" signal "GND7")
		(2 "B.Cu" signal "BOTTOM")
		(9 "F.Adhes" user "F.Adhesive")
		(11 "B.Adhes" user "B.Adhesive")
		(13 "F.Paste" user "Package Geometry/Pastemask Top")
		(15 "B.Paste" user "Package Geometry/Pastemask Bottom")
		(5 "F.SilkS" user "Ref Des/Silkscreen Top")
		(7 "B.SilkS" user "Ref Des/Silkscreen Bottom")
		(1 "F.Mask" user "Board Geometry/Soldermask Top")
		(3 "B.Mask" user "Board Geometry/Soldermask Bottom")
		(17 "Dwgs.User" user "User.Drawings")
		(19 "Cmts.User" user "User.Comments")
		(21 "Eco1.User" user "User.Eco1")
		(23 "Eco2.User" user "User.Eco2")
		(25 "Edge.Cuts" user "Board Geometry/Outline")
		(27 "Margin" user)
		(31 "F.CrtYd" user "Package Geometry/Place Bound Top")
		(29 "B.CrtYd" user "Package Geometry/Place Bound Bottom")
		(35 "F.Fab" user "Ref Des/Assembly Top")
		(33 "B.Fab" user "Ref Des/Assembly Bottom")
	)
	(footprint ""
		(layer "B.Cu")
		(at 144.51711 -28.989528 180)
		(property "Reference" "C2321"
			(at 0 0 0)
			(layer "B.SilkS")
			(hide yes)
			(effects
				(font
					(size 1.27 1.27)
				)
				(justify mirror)
			)
		)
		(property "Value" ""
			(at 0 0 0)
			(layer "B.Fab")
			(effects
				(font
					(size 1.27 1.27)
				)
				(justify mirror)
			)
		)
		(duplicate_pad_numbers_are_jumpers no)
		(fp_line
			(start 0.7874 0.4064)
			(end 0.7874 -0.4064)
			(stroke
				(width 0.1524)
				(type default)
			)
			(layer "B.SilkS")
		)
		(fp_line
			(start 0.7874 -0.4064)
			(end -0.7874 -0.4064)
			(stroke
				(width 0.1524)
				(type default)
			)
			(layer "B.SilkS")
		)
		(fp_line
			(start -0.7874 0.4064)
			(end 0.7874 0.4064)
			(stroke
				(width 0.1524)
				(type default)
			)
			(layer "B.SilkS")
		)
		(fp_line
			(start -0.7874 -0.4064)
			(end -0.7874 0.4064)
			(stroke
				(width 0.1524)
				(type default)
			)
			(layer "B.SilkS")
		)
		(fp_line
			(start 0.67945 0.3048)
			(end 0.67945 -0.305054)
			(stroke
				(width 0.1)
				(type default)
			)
			(layer "B.Fab")
		)
		(fp_line
			(start 0.67945 -0.305054)
			(end 0.12065 -0.305054)
			(stroke
				(width 0.1)
				(type default)
			)
			(layer "B.Fab")
		)
		(fp_line
			(start 0.12065 0.3048)
			(end 0.67945 0.3048)
			(stroke
				(width 0.1)
				(type default)
			)
			(layer "B.Fab")
		)
		(fp_line
			(start 0.12065 0.2794)
			(end 0.12065 0.3048)
			(stroke
				(width 0.1)
				(type default)
			)
			(layer "B.Fab")
		)
		(fp_line
			(start 0.12065 -0.2794)
			(end -0.12065 -0.2794)
			(stroke
				(width 0.1)
				(type default)
			)
			(layer "B.Fab")
		)
		(fp_line
			(start 0.12065 -0.305054)
			(end 0.12065 -0.2794)
			(stroke
				(width 0.1)
				(type default)
			)
			(layer "B.Fab")
		)
		(fp_line
			(start -0.120396 0.3048)
			(end -0.120396 0.2794)
			(stroke
				(width 0.1)
				(type default)
			)
			(layer "B.Fab")
		)
		(fp_line
			(start -0.120396 0.2794)
			(end 0.12065 0.2794)
			(stroke
				(width 0.1)
				(type default)
			)
			(layer "B.Fab")
		)
		(fp_line
			(start -0.12065 -0.2794)
			(end -0.12065 -0.3048)
			(stroke
				(width 0.1)
				(type default)
			)
			(layer "B.Fab")
		)
		(fp_line
			(start -0.12065 -0.3048)
			(end -0.67945 -0.3048)
			(stroke
				(width 0.1)
				(type default)
			)
			(layer "B.Fab")
		)
		(fp_line
			(start -0.67945 0.3048)
			(end -0.120396 0.3048)
			(stroke
				(width 0.1)
				(type default)
			)
			(layer "B.Fab")
		)
		(fp_line
			(start -0.67945 -0.3048)
			(end -0.67945 0.3048)
			(stroke
				(width 0.1)
				(type default)
			)
			(layer "B.Fab")
		)
		(pad "1" smd circle
			(at 0.40005 0)
			(size 0 0)
			(layers "B.Cu" "B.Mask" "B.Paste")
			(net "PD_USB_HUB_2_RSTN")
		)
		(pad "2" smd circle
			(at -0.40005 0)
			(size 0 0)
			(layers "B.Cu" "B.Mask" "B.Paste")
			(net "GND")
		)
	)
	(footprint ""
		(layer "B.Cu")
		(at 70.369684 -190.744856 90)
		(property "Reference" "R57"
			(at 0 0 90)
			(layer "B.SilkS")
			(hide yes)
			(effects
				(font
					(size 1.27 1.27)
				)
				(justify mirror)
			)
		)
		(property "Value" ""
			(at 0 0 90)
			(layer "B.Fab")
			(effects
				(font
					(size 1.27 1.27)
				)
				(justify mirror)
			)
		)
		(duplicate_pad_numbers_are_jumpers no)
		(fp_line
			(start 0.7874 -0.4064)
			(end -0.7874 -0.4064)
			(stroke
				(width 0.1524)
				(type default)
			)
			(layer "B.SilkS")
		)
		(fp_line
			(start -0.7874 -0.4064)
			(end -0.7874 0.4064)
			(stroke
				(width 0.1524)
				(type default)
			)
			(layer "B.SilkS")
		)
		(fp_line
			(start 0.7874 0.4064)
			(end 0.7874 -0.4064)
			(stroke
				(width 0.1524)
				(type default)
			)
			(layer "B.SilkS")
		)
		(fp_line
			(start -0.7874 0.4064)
			(end 0.7874 0.4064)
			(stroke
				(width 0.1524)
				(type default)
			)
			(layer "B.SilkS")
		)
		(fp_line
			(start 0.67945 -0.305054)
			(end 0.12065 -0.305054)
			(stroke
				(width 0.1)
				(type default)
			)
			(layer "B.Fab")
		)
		(fp_line
			(start 0.12065 -0.305054)
			(end 0.12065 -0.2794)
			(stroke
				(width 0.1)
				(type default)
			)
			(layer "B.Fab")
		)
		(fp_line
			(start -0.12065 -0.3048)
			(end -0.67945 -0.3048)
			(stroke
				(width 0.1)
				(type default)
			)
			(layer "B.Fab")
		)
		(fp_line
			(start -0.67945 -0.3048)
			(end -0.67945 0.3048)
			(stroke
				(width 0.1)
				(type default)
			)
			(layer "B.Fab")
		)
		(fp_line
			(start 0.12065 -0.2794)
			(end -0.12065 -0.2794)
			(stroke
				(width 0.1)
				(type default)
			)
			(layer "B.Fab")
		)
		(fp_line
			(start -0.12065 -0.2794)
			(end -0.12065 -0.3048)
			(stroke
				(width 0.1)
				(type default)
			)
			(layer "B.Fab")
		)
		(fp_line
			(start 0.12065 0.2794)
			(end 0.12065 0.3048)
			(stroke
				(width 0.1)
				(type default)
			)
			(layer "B.Fab")
		)
		(fp_line
			(start -0.120396 0.2794)
			(end 0.12065 0.2794)
			(stroke
				(width 0.1)
				(type default)
			)
			(layer "B.Fab")
		)
		(fp_line
			(start 0.67945 0.3048)
			(end 0.67945 -0.305054)
			(stroke
				(width 0.1)
				(type default)
			)
			(layer "B.Fab")
		)
		(fp_line
			(start 0.12065 0.3048)
			(end 0.67945 0.3048)
			(stroke
				(width 0.1)
				(type default)
			)
			(layer "B.Fab")
		)
		(fp_line
			(start -0.120396 0.3048)
			(end -0.120396 0.2794)
			(stroke
				(width 0.1)
				(type default)
			)
			(layer "B.Fab")
		)
		(fp_line
			(start -0.67945 0.3048)
			(end -0.120396 0.3048)
			(stroke
				(width 0.1)
				(type default)
			)
			(layer "B.Fab")
		)
		(pad "1" smd circle
			(at 0.40005 0 270)
			(size 0 0)
			(layers "B.Cu" "B.Mask" "B.Paste")
			(net "SVID_ALERT0_CPU1_N")
		)
		(pad "2" smd circle
			(at -0.40005 0 270)
			(size 0 0)
			(layers "B.Cu" "B.Mask" "B.Paste")
			(net "SVID_ALERT0_CPU1_R_N")
		)
	)
)
